# BARRELEYE_G2-FPDB_POST-EVT-HW-EBOM-X00_20161123-add_2nd_source_X08-20161215-Final-b.xls — POST (bom)
| FOXCONN TECHNOLOGY GROUP |  |  |  |  |  |  |  |  |  |  |  |  |  |  |  |  |  |  |
| BILL OF MATERIAL |  |  |  |  |  |  |  |  |  |  |  |  |  |  |  |  |  |  |
| REV OF  BOM | X07 | CUSTOMER |  | <name> |  | CUSTOMER P/N |  | PWA P/N： | PWA DESCRIPTION |  |  |  | PRODUCT CODE |  |  | PWA  REV |  | DATE |
| Sourcing (Single/Sole/Multi) | Critical Commodity (Y or N) | Component Class (1, 2, other) | Customer PSL (Y or N) | Line Item | Item Number | Foxconn P/N | Customer P/N | Part Description | Manufacturer  Full Name | Manufacturer  Part Number | Qty | RoHS Status | Location | CC Qual Build: | Qual by (Customer / ODM ?) | The Date of Change Part or Add 2nd Source | Configuration Identifier | Customer Comments |
|  |  |  |  | 1 | 1 | 0101E6H00-000-G |  | PCB,Barreleye-G2-Post_Card EVT-X00,OSP,Red,4L,0.86*0.67,G | GCE | 0101E6H00-000-G | 1 |  | PCB |  |  |  |  |  |
|  |  |  |  |  | 1 | 0101E6H00-000-G |  | PCB,Barreleye-G2-Post_Card EVT-X00,OSP,Red,4L,0.86*0.67,G | FOUNDER | 0101E6H00-000-G |  |  |  |  |  |  |  |  |
|  |  |  |  | 2 | 2 | 620101T02-015-G | - | CAP,100nF,+/-10%,X7R,16V,G,SMD0402 | MURATA | GRM155R71C104K | 2 |  | C71,C72 |  |  |  |  |  |
|  |  |  |  |  | 2 | 620101T00-012-G |  | CAP,100nF,+/-10%,X7R,16V,G,SMD0402 | WALSIN | 0402B104K160CT |  |  |  |  |  |  |  |  |
|  |  |  |  |  | 2 | 620101T00-026-G |  | CAP,100nF,+/-10%,X7R,16V,G,SMD0402 | SAMSUNG | CL05B104KO5NNNC |  |  |  |  |  |  |  |  |
|  |  |  |  |  | 2 | 620101T00-015-G |  | CAP,100nF,+/-10%,X7R,16V,G,SMD0402 | MURATA | GRM155R71C104KA88D |  |  |  |  |  |  |  |  |
|  |  |  |  | 3 | 3 | 52113DU00-289-G |  | LED,Hyper Red,LTS-2307CKD-P,G,5V,25mA,G,SMD-10 | LITE-ON | LTS-2307CKD-P | 2 |  | LED1,LED2 |  |  |  |  |  |
|  |  |  |  | 4 | 4 | 610107C00-017-G |  | RES,10KOhm,+/-5%,1/16W,G,SMD0402 | KOA | RK73B1ETTP103J | 2 |  | R250,R259 |  |  |  |  |  |
|  |  |  |  |  | 4 | 610107C00-012-G |  | RES,10KOhm,+/-5%,1/16W,G,SMD0402 | WALSIN | WR04X103JTL |  |  |  |  |  |  |  |  |
|  |  |  |  |  | 4 | 610107C00-011-G |  | RES,10KOhm,+/-5%,1/16W,G,SMD0402 | YAGEO | RC0402JR-0710KL |  |  |  |  |  |  |  |  |
|  |  |  |  |  | 4 | 610107C00-044-G |  | RES,10KOhm,+/-5%,1/16W,G,SMD0402 | TA-I | RM04JTN103 |  |  |  |  |  |  |  |  |
|  |  |  |  |  | 4 | 610107C00-024-G |  | RES,10KOhm,+/-5%,1/16W,G,SMD0402 | PANASONIC | ERJ2GEJ103X |  |  |  |  |  |  |  |  |
|  |  |  |  |  | 4 | 610107C00-029-G |  | RES,10KOhm,+/-5%,1/16W,G,SMD0402 | VISHAY | CRCW040210K0JNED |  |  |  |  |  |  |  |  |
|  |  |  |  | 5 | 5 | 61010L300-017-G | - | RES,1KOhm,+/-1%,1/16W,G,SMD0402 | KOA | RK73H1ETTP1001F | 1 |  | R251 |  |  |  |  |  |
|  |  |  |  |  | 5 | 61010L300-012-G |  | RES,1KOhm,+/-1%,1/16W,G,SMD0402 | WALSIN | WR04X1001FTL |  |  |  |  |  |  |  |  |
|  |  |  |  |  | 5 | 61010L300-011-G |  | RES,1KOhm,+/-1%,1/16W,G,SMD0402 | YAGEO | RC0402FR-071KL |  |  |  |  |  |  |  |  |
|  |  |  |  |  | 5 | 61010L300-044-G |  | RES,1KOhm,+/-1%,1/16W,G,SMD0402 | TA-I | RM04FTN1001 |  |  |  |  |  |  |  |  |
|  |  |  |  |  | 5 | 61010L300-024-G |  | RES,1KOhm,+/-1%,1/16W,G,SMD0402 | PANASONIC | ERJ2RKF1001X |  |  |  |  |  |  |  |  |
|  |  |  |  |  | 5 | 61010L300-029-G |  | RES,1KOhm,+/-1%,1/16W,G,SMD0402 | VISHAY | CRCW04021K00FKED |  |  |  |  |  |  |  |  |
|  |  |  |  | 6 | 6 | 61010JY00-017-G | - | RES,220 Ohm,+/-5%,1/16W,G,SMD0402 | KOA | RK73B1ETTP221J | 15 |  | R252,R253,R254,R255,R256,R257,R258,R260,R261,R262,R263,R264,R265,R266,R267 |  |  |  |  |  |
|  |  |  |  |  | 6 | 61010JY00-012-G |  | RES,220 Ohm,+/-5%,1/16W,G,SMD0402 | WALSIN | WR04X221JTL |  |  |  |  |  |  |  |  |
|  |  |  |  |  | 6 | 61010JY00-011-G |  | RES,220 Ohm,+/-5%,1/16W,G,SMD0402 | YAGEO | RC0402JR-07220RL |  |  |  |  |  |  |  |  |
|  |  |  |  |  | 6 | 61010JY00-044-G |  | RES,220 Ohm,+/-5%,1/16W,G,SMD0402 | TA-I | RM04JTN221 |  |  |  |  |  |  |  |  |
|  |  |  |  | 7 | 7 | 310200R00-183-G | - | IC,Trigger,SN74LV164ADBR,2~5.5V,G,SSOP-14,SMD | TI | SN74LV164ADBR | 2 |  | U25,U26 |  |  |  |  |  |
|  |  |  |  | 8 | 8 | 3406ARH00-309-G |  | CONN,Header,Socket,V/T,Bla,2.54mm,10u,G,DIP-8 | SAMTEC | ESQ-104-33-L-D | 1 |  | J10 |  |  |  |  |  |
